# BASEBOARD_FAB2 (Tioga Pass) — schematic netlist excerpt (pin names and nets, part order shuffled) for the footprints in the layout excerpt that follows; sources: Cadence DE-HDL packaged netlist, KiCad conversion of Wiwynn_Tioga_Pass_MB.brd

R767  RES  0.0 5% CHIP  pkg 0402  page 244 : A = P3E_CPU0_PE1_PCH_RXP<15> ; B = P3E_CPU0_PE1_PCH_CON_RXP<15>
C5U7  CAP_A  47UF 4V 20% X5R  pkg 0603V  page 217 : A = PVDDQ_ABC ; B = GND
C9G21  CAP  47.0PF 50V 5% COG  pkg 0402LF  page 169 : A = A_P5V_STBY_SCALED ; B = GND

(kicad_pcb
	(version 20260206)
	(generator "pcbnew")
	(generator_version "10.0")
	(general
		(thickness 1.6)
		(legacy_teardrops no)
	)
	(paper "A4")
	(title_block
		(title "Wiwynn_Tioga_Pass_MB.brd")
		(comment 1 "Tioga Pass / footprints 2914-2916 of 4770")
	)
	(layers
		(0 "F.Cu" signal "TOP")
		(4 "In1.Cu" signal "L2GND")
		(6 "In2.Cu" signal "L3")
		(8 "In3.Cu" signal "L4GND")
		(10 "In4.Cu" signal "L5")
		(12 "In5.Cu" signal "L6GND")
		(14 "In6.Cu" signal "L7VCC")
		(16 "In7.Cu" signal "L8VCC")
		(18 "In8.Cu" signal "L9GND")
		(20 "In9.Cu" signal "L10")
		(22 "In10.Cu" signal "L11GND")
		(24 "In11.Cu" signal "L12")
		(26 "In12.Cu" signal "L13GND")
		(2 "B.Cu" signal "BOTTOM")
		(9 "F.Adhes" user "F.Adhesive")
		(11 "B.Adhes" user "B.Adhesive")
		(13 "F.Paste" user "Package Geometry/Pastemask Top")
		(15 "B.Paste" user "Package Geometry/Pastemask Bottom")
		(5 "F.SilkS" user "Ref Des/Silkscreen Top")
		(7 "B.SilkS" user "Ref Des/Silkscreen Bottom")
		(1 "F.Mask" user "Board Geometry/Soldermask Top")
		(3 "B.Mask" user "Board Geometry/Soldermask Bottom")
		(17 "Dwgs.User" user "User.Drawings")
		(19 "Cmts.User" user "User.Comments")
		(21 "Eco1.User" user "User.Eco1")
		(23 "Eco2.User" user "User.Eco2")
		(25 "Edge.Cuts" user "Board Geometry/Outline")
		(27 "Margin" user)
		(31 "F.CrtYd" user "Package Geometry/Place Bound Top")
		(29 "B.CrtYd" user "Package Geometry/Place Bound Bottom")
		(35 "F.Fab" user "Ref Des/Assembly Top")
		(33 "B.Fab" user "Ref Des/Assembly Bottom")
	)
	(footprint ""
		(layer "B.Cu")
		(at 402.881846 -24.838152)
		(property "Reference" "C9G21"
			(at 0 0 0)
			(layer "B.SilkS")
			(hide yes)
			(effects
				(font
					(size 1.27 1.27)
				)
				(justify mirror)
			)
		)
		(property "Value" ""
			(at 0 0 0)
			(layer "B.Fab")
			(effects
				(font
					(size 1.27 1.27)
				)
				(justify mirror)
			)
		)
		(duplicate_pad_numbers_are_jumpers no)
		(fp_poly
			(pts
				(xy -0.3048 -0.1016) (xy -0.3048 0.9906) (xy 0.3048 0.9906) (xy 0.3048 -0.1016)
			)
			(stroke
				(width 0)
				(type default)
			)
			(fill no)
			(layer "B.CrtYd")
		)
		(fp_line
			(start -0.3048 -0.1016)
			(end 0.3048 -0.1016)
			(stroke
				(width 0.1)
				(type default)
			)
			(layer "B.Fab")
		)
		(fp_line
			(start -0.3048 0.9906)
			(end -0.3048 -0.1016)
			(stroke
				(width 0.1)
				(type default)
			)
			(layer "B.Fab")
		)
		(fp_line
			(start 0.3048 -0.1016)
			(end 0.3048 0.9906)
			(stroke
				(width 0.1)
				(type default)
			)
			(layer "B.Fab")
		)
		(fp_line
			(start 0.3048 0.9906)
			(end -0.3048 0.9906)
			(stroke
				(width 0.1)
				(type default)
			)
			(layer "B.Fab")
		)
		(pad "1" smd rect
			(at 0 0 180)
			(size 0.508 0.508)
			(layers "B.Cu" "B.Mask" "B.Paste")
			(net "A_P5V_STBY_SCALED")
		)
		(pad "2" smd rect
			(at 0 0.889 180)
			(size 0.508 0.508)
			(layers "B.Cu" "B.Mask" "B.Paste")
			(net "GND")
		)
		(zone
			(layer "B.Cu")
			(hatch none 0.5)
			(connect_pads
				(clearance 0)
			)
			(min_thickness 0.25)
			(keepout
				(tracks allowed)
				(vias not_allowed)
				(pads allowed)
				(copperpour not_allowed)
				(footprints allowed)
			)
			(placement
				(enabled no)
				(sheetname "")
			)
			(fill
				(thermal_gap 0.5)
				(thermal_bridge_width 0.5)
				(island_removal_mode 0)
			)
			(polygon
				(pts
					(xy 403.135846 -24.584152) (xy 402.627846 -24.584152) (xy 402.627846 -24.203152) (xy 403.135846 -24.203152)
				)
			)
		)
		(zone
			(layer "B.Cu")
			(hatch none 0.5)
			(connect_pads
				(clearance 0)
			)
			(min_thickness 0.25)
			(keepout
				(tracks not_allowed)
				(vias allowed)
				(pads allowed)
				(copperpour not_allowed)
				(footprints allowed)
			)
			(placement
				(enabled no)
				(sheetname "")
			)
			(fill
				(thermal_gap 0.5)
				(thermal_bridge_width 0.5)
				(island_removal_mode 0)
			)
			(polygon
				(pts
					(xy 403.135846 -24.203152) (xy 402.627846 -24.203152) (xy 402.627846 -24.584152) (xy 403.135846 -24.584152)
				)
			)
		)
	)
	(footprint ""
		(layer "B.Cu")
		(at 252.1585 -8.1534 -90)
		(property "Reference" "C5U7"
			(at -1.848866 0.752348 270)
			(unlocked yes)
			(layer "B.SilkS")
			(effects
				(font
					(size 1.27 0.9652)
					(thickness 0.1524)
				)
				(justify mirror)
			)
		)
		(property "Value" ""
			(at 0 0 90)
			(layer "B.Fab")
			(effects
				(font
					(size 1.27 1.27)
				)
				(justify mirror)
			)
		)
		(duplicate_pad_numbers_are_jumpers no)
		(fp_rect
			(start 0.500126 1.598422)
			(end -0.500126 -0.201422)
			(stroke
				(width 0)
				(type default)
			)
			(fill no)
			(layer "B.CrtYd")
		)
		(fp_line
			(start -0.500126 1.598422)
			(end 0.500126 1.598422)
			(stroke
				(width 0.1)
				(type default)
			)
			(layer "B.Fab")
		)
		(fp_line
			(start 0.500126 1.598422)
			(end 0.500126 -0.201422)
			(stroke
				(width 0.1)
				(type default)
			)
			(layer "B.Fab")
		)
		(fp_line
			(start -0.500126 -0.201422)
			(end -0.500126 1.598422)
			(stroke
				(width 0.1)
				(type default)
			)
			(layer "B.Fab")
		)
		(fp_line
			(start 0.500126 -0.201422)
			(end -0.500126 -0.201422)
			(stroke
				(width 0.1)
				(type default)
			)
			(layer "B.Fab")
		)
		(pad "1" smd rect
			(at 0 0 180)
			(size 0.889 0.9906)
			(layers "B.Cu" "B.Mask" "B.Paste")
			(net "PVDDQ_ABC")
		)
		(pad "2" smd rect
			(at 0 1.397 180)
			(size 0.889 0.9906)
			(layers "B.Cu" "B.Mask" "B.Paste")
			(net "GND")
		)
		(zone
			(layer "B.Cu")
			(hatch none 0.5)
			(connect_pads
				(clearance 0)
			)
			(min_thickness 0.25)
			(keepout
				(tracks not_allowed)
				(vias allowed)
				(pads allowed)
				(copperpour not_allowed)
				(footprints allowed)
			)
			(placement
				(enabled no)
				(sheetname "")
			)
			(fill
				(thermal_gap 0.5)
				(thermal_bridge_width 0.5)
				(island_removal_mode 0)
			)
			(polygon
				(pts
					(xy 251.206 -7.6581) (xy 251.714 -7.6581) (xy 251.714 -8.6487) (xy 251.206 -8.6487)
				)
			)
		)
		(zone
			(layer "B.Cu")
			(hatch none 0.5)
			(connect_pads
				(clearance 0)
			)
			(min_thickness 0.25)
			(keepout
				(tracks allowed)
				(vias not_allowed)
				(pads allowed)
				(copperpour not_allowed)
				(footprints allowed)
			)
			(placement
				(enabled no)
				(sheetname "")
			)
			(fill
				(thermal_gap 0.5)
				(thermal_bridge_width 0.5)
				(island_removal_mode 0)
			)
			(polygon
				(pts
					(xy 251.206 -7.6581) (xy 251.714 -7.6581) (xy 251.714 -8.6487) (xy 251.206 -8.6487)
				)
			)
		)
	)
	(footprint ""
		(layer "B.Cu")
		(at 354.289614 -126.624842 -90)
		(property "Reference" "R767"
			(at 0.8382 -0.67818 270)
			(unlocked yes)
			(layer "B.SilkS")
			(effects
				(font
					(size 0.4064 0.254)
					(thickness 0.1524)
				)
				(justify left mirror)
			)
		)
		(property "Value" ""
			(at 0 0 90)
			(layer "B.Fab")
			(effects
				(font
					(size 1.27 1.27)
				)
				(justify mirror)
			)
		)
		(duplicate_pad_numbers_are_jumpers no)
		(fp_poly
			(pts
				(xy 0.2794 -0.1016) (xy -0.2794 -0.1016) (xy -0.2794 0.9906) (xy 0.2794 0.9906)
			)
			(stroke
				(width 0)
				(type default)
			)
			(fill no)
			(layer "B.CrtYd")
		)
		(fp_line
			(start -0.2794 0.9906)
			(end -0.2794 -0.1016)
			(stroke
				(width 0.1)
				(type default)
			)
			(layer "B.Fab")
		)
		(fp_line
			(start 0.2794 0.9906)
			(end -0.2794 0.9906)
			(stroke
				(width 0.1)
				(type default)
			)
			(layer "B.Fab")
		)
		(fp_line
			(start -0.2794 -0.1016)
			(end 0.2794 -0.1016)
			(stroke
				(width 0.1)
				(type default)
			)
			(layer "B.Fab")
		)
		(fp_line
			(start 0.2794 -0.1016)
			(end 0.2794 0.9906)
			(stroke
				(width 0.1)
				(type default)
			)
			(layer "B.Fab")
		)
		(pad "1" smd rect
			(at 0 0 90)
			(size 0.508 0.508)
			(layers "B.Cu" "B.Mask" "B.Paste")
			(net "P3E_CPU0_PE1_PCH_RXP<15>")
		)
		(pad "2" smd rect
			(at 0 0.889 90)
			(size 0.508 0.508)
			(layers "B.Cu" "B.Mask" "B.Paste")
			(net "P3E_CPU0_PE1_PCH_CON_RXP<15>")
		)
		(zone
			(layer "B.Cu")
			(hatch none 0.5)
			(connect_pads
				(clearance 0)
			)
			(min_thickness 0.25)
			(keepout
				(tracks not_allowed)
				(vias allowed)
				(pads allowed)
				(copperpour not_allowed)
				(footprints allowed)
			)
			(placement
				(enabled no)
				(sheetname "")
			)
			(fill
				(thermal_gap 0.5)
				(thermal_bridge_width 0.5)
				(island_removal_mode 0)
			)
			(polygon
				(pts
					(xy 353.654614 -126.370842) (xy 353.654614 -126.878842) (xy 354.035614 -126.878842) (xy 354.035614 -126.370842)
				)
			)
		)
		(zone
			(layer "B.Cu")
			(hatch none 0.5)
			(connect_pads
				(clearance 0)
			)
			(min_thickness 0.25)
			(keepout
				(tracks allowed)
				(vias not_allowed)
				(pads allowed)
				(copperpour not_allowed)
				(footprints allowed)
			)
			(placement
				(enabled no)
				(sheetname "")
			)
			(fill
				(thermal_gap 0.5)
				(thermal_bridge_width 0.5)
				(island_removal_mode 0)
			)
			(polygon
				(pts
					(xy 354.035614 -126.370842) (xy 354.035614 -126.878842) (xy 353.654614 -126.878842) (xy 353.654614 -126.370842)
				)
			)
		)
	)
)
